# BASEBOARD_FAB2 (Tioga Pass) — schematic netlist excerpt (pin names and nets, part order shuffled) for the footprints in the layout excerpt that follows; sources: Cadence DE-HDL packaged netlist, KiCad conversion of Wiwynn_Tioga_Pass_MB.brd

J6U1  SCONN288_H44441003  SCONN  pkg PIP  page 46
  \12v\(1)  = P12V_NVDIMM_ABC
  VSS(93)  = GND
  DQ(4)  = M_B_DQ<4>
  VSS(92)  = GND
  DQ(0)  = M_B_DQ<0>
  VSS(91)  = GND
  DQS9P  = M_B_DQS_DP<9>
  DQS9N  = M_B_DQS_DN<9>
  VSS(90)  = GND
  DQ(6)  = M_B_DQ<6>
  VSS(89)  = GND
  DQ(2)  = M_B_DQ<2>
  VSS(88)  = GND
  DQ(12)  = M_B_DQ<12>
  VSS(87)  = GND
  DQ(8)  = M_B_DQ<8>
  VSS(86)  = GND
  DQS10P  = M_B_DQS_DP<10>
  DQS10N  = M_B_DQS_DN<10>
  VSS(85)  = GND
  DQ(14)  = M_B_DQ<14>
  VSS(84)  = GND
  DQ(10)  = M_B_DQ<10>
  VSS(83)  = GND
  DQ(20)  = M_B_DQ<20>
  VSS(82)  = GND
  DQ(16)  = M_B_DQ<16>
  VSS(81)  = GND
  DQS11P  = M_B_DQS_DP<11>
  DQS11N  = M_B_DQS_DN<11>
  VSS(80)  = GND
  DQ(22)  = M_B_DQ<22>
  VSS(79)  = GND
  DQ(18)  = M_B_DQ<18>
  VSS(78)  = GND
  DQ(28)  = M_B_DQ<28>
  VSS(77)  = GND
  DQ(24)  = M_B_DQ<24>
  VSS(76)  = GND
  DQS12P  = M_B_DQS_DP<12>
  DQS12N  = M_B_DQS_DN<12>
  VSS(75)  = GND
  DQ(30)  = M_B_DQ<30>
  VSS(74)  = GND
  DQ(26)  = M_B_DQ<26>
  VSS(73)  = GND
  CB(4)  = M_B_ECC<4>
  VSS(72)  = GND
  CB(0)  = M_B_ECC<0>
  VSS(71)  = GND
  DQS17P  = M_B_DQS_DP<17>
  DQS17N  = M_B_DQS_DN<17>
  VSS(70)  = GND
  CB(6)  = M_B_ECC<6>
  VSS(69)  = GND
  CB(2)  = M_B_ECC<2>
  VSS(68)  = GND
  RESET_N  = M_ABC_RST_N
  VDD(25)  = PVDDQ_ABC
  CKE(0)  = M_B_CKE<2>
  VDD(24)  = PVDDQ_ABC
  ACT_N  = M_B_ACT_N
  BG(0)  = M_B_BG<0>
  VDD(23)  = PVDDQ_ABC
  A12  = M_B_MA<12>
  A9  = M_B_MA<9>
  VDD(22)  = PVDDQ_ABC
  A8  = M_B_MA<8>
  A6  = M_B_MA<6>
  VDD(21)  = PVDDQ_ABC
  A3  = M_B_MA<3>
  A1  = M_B_MA<1>
  VDD(20)  = PVDDQ_ABC
  CK0P  = M_B_CLK_DP<2>
  CK0N  = M_B_CLK_DN<2>
  VDD(19)  = PVDDQ_ABC
  VTT(1)  = PVTT_ABC
  EVENT_N  = FM_DIMM_EVENT_COD_N
  A0  = M_B_MA<0>
  VDD(18)  = PVDDQ_ABC
  BA(0)  = M_B_BA<0>
  A16_RAS_N  = M_B_MA<16>
  VDD(17)  = PVDDQ_ABC
  S0_N  = M_B_CS_N<4>
  VDD(16)  = PVDDQ_ABC
  A15_CAS_N  = M_B_MA<15>
  ODT(0)  = M_B_ODT<2>
  VDD(15)  = PVDDQ_ABC
  S1_N  = M_B_CS_N<5>
  VDD(14)  = PVDDQ_ABC
  ODT(1)  = M_B_ODT<3>
  VDD(13)  = PVDDQ_ABC
  S2_N_C(0)  = M_B_CS_N<6>
  VSS(67)  = GND
  DQ(36)  = M_B_DQ<36>
  VSS(66)  = GND
  DQ(32)  = M_B_DQ<32>
  VSS(65)  = GND
  DQS13P  = M_B_DQS_DP<13>
  DQS13N  = M_B_DQS_DN<13>
  VSS(64)  = GND
  DQ(38)  = M_B_DQ<38>
  VSS(63)  = GND
  DQ(34)  = M_B_DQ<34>
  VSS(62)  = GND
  DQ(44)  = M_B_DQ<44>
  VSS(61)  = GND
  DQ(40)  = M_B_DQ<40>
  VSS(60)  = GND
  DQS14P  = M_B_DQS_DP<14>
  DQS14N  = M_B_DQS_DN<14>
  VSS(59)  = GND
  DQ(46)  = M_B_DQ<46>
  VSS(58)  = GND
  DQ(42)  = M_B_DQ<42>
  VSS(57)  = GND
  DQ(52)  = M_B_DQ<52>
  VSS(56)  = GND
  DQ(48)  = M_B_DQ<48>
  VSS(55)  = GND
  DQS15P  = M_B_DQS_DP<15>
  DQS15N  = M_B_DQS_DN<15>
  VSS(54)  = GND
  DQ(54)  = M_B_DQ<54>
  VSS(53)  = GND
  DQ(50)  = M_B_DQ<50>
  VSS(52)  = GND
  DQ(60)  = M_B_DQ<60>
  VSS(51)  = GND
  DQ(56)  = M_B_DQ<56>
  VSS(50)  = GND
  DQS16P  = M_B_DQS_DP<16>
  DQS16N  = M_B_DQS_DN<16>
  VSS(49)  = GND
  DQ(62)  = M_B_DQ<62>
  VSS(48)  = GND
  DQ(58)  = M_B_DQ<58>
  VSS(47)  = GND
  SA(0)  = PVPP_ABC
  SA(1)  = PVPP_ABC
  SCL  = SMB_DDR_ABC_VPP_SCL
  VPP(4)  = PVPP_ABC
  VPP(3)  = PVPP_ABC
  RFU(2)  = TP_CH_B_DIMM_B1_RFU_2
  \12v\(0)  = P12V_NVDIMM_ABC
  VREFCA  = M_B_VREF
  VSS(46)  = GND
  DQ(5)  = M_B_DQ<5>
  VSS(45)  = GND
  DQ(1)  = M_B_DQ<1>
  VSS(44)  = GND
  DQS0N  = M_B_DQS_DN<0>
  DQS0P  = M_B_DQS_DP<0>
  VSS(43)  = GND
  DQ(7)  = M_B_DQ<7>
  VSS(42)  = GND
  DQ(3)  = M_B_DQ<3>
  VSS(41)  = GND
  DQ(13)  = M_B_DQ<13>
  VSS(40)  = GND
  DQ(9)  = M_B_DQ<9>
  VSS(39)  = GND
  DQS1N  = M_B_DQS_DN<1>
  DQS1P  = M_B_DQS_DP<1>
  VSS(38)  = GND
  DQ(15)  = M_B_DQ<15>
  VSS(37)  = GND
  DQ(11)  = M_B_DQ<11>
  VSS(36)  = GND
  DQ(21)  = M_B_DQ<21>
  VSS(35)  = GND
  DQ(17)  = M_B_DQ<17>
  VSS(34)  = GND
  DQS2N  = M_B_DQS_DN<2>
  DQS2P  = M_B_DQS_DP<2>
  VSS(33)  = GND
  DQ(23)  = M_B_DQ<23>
  VSS(32)  = GND
  DQ(19)  = M_B_DQ<19>
  VSS(31)  = GND
  DQ(29)  = M_B_DQ<29>
  VSS(30)  = GND
  DQ(25)  = M_B_DQ<25>
  VSS(29)  = GND
  DQS3N  = M_B_DQS_DN<3>
  DQS3P  = M_B_DQS_DP<3>
  VSS(28)  = GND
  DQ(31)  = M_B_DQ<31>
  VSS(27)  = GND
  DQ(27)  = M_B_DQ<27>
  VSS(26)  = GND
  CB(5)  = M_B_ECC<5>
  VSS(25)  = GND
  CB(1)  = M_B_ECC<1>
  VSS(24)  = GND
  DQS8N  = M_B_DQS_DN<8>
  DQS8P  = M_B_DQS_DP<8>
  VSS(23)  = GND
  CB(7)  = M_B_ECC<7>
  VSS(22)  = GND
  CB(3)  = M_B_ECC<3>
  VSS(21)  = GND
  CKE(1)  = M_B_CKE<3>
  VDD(12)  = PVDDQ_ABC
  RFU(0)  = TP_CH_B_DIMM_B1_RFU_0
  VDD(11)  = PVDDQ_ABC
  BG(1)  = M_B_BG<1>
  ALERT_N  = M_B_ALERT_N
  VDD(10)  = PVDDQ_ABC
  A11  = M_B_MA<11>
  A7  = M_B_MA<7>
  VDD(9)  = PVDDQ_ABC
  A5  = M_B_MA<5>
  A4  = M_B_MA<4>
  VDD(8)  = PVDDQ_ABC
  A2  = M_B_MA<2>
  VDD(7)  = PVDDQ_ABC
  CK1P  = M_B_CLK_DP<3>
  CK1N  = M_B_CLK_DN<3>
  VDD(6)  = PVDDQ_ABC
  VTT(0)  = PVTT_ABC
  PAR  = M_B_PAR
  VDD(5)  = PVDDQ_ABC
  BA(1)  = M_B_BA<1>
  A10  = M_B_MA<10>
  VDD(4)  = PVDDQ_ABC
  RFU(1)  = TP_CH_B_DIMM_B1_RFU_1
  A14_WE_N  = M_B_MA<14>
  VDD(3)  = PVDDQ_ABC
  SAVE_N_NC  = FM_ADR_COMPLETE_ABC_N
  VDD(2)  = PVDDQ_ABC
  A13  = M_B_MA<13>
  VDD(1)  = PVDDQ_ABC
  A17  = M_B_MA<17>
  C(2)  = M_B_C<2>
  VDD(0)  = PVDDQ_ABC
  S3_N_C(1)  = M_B_CS_N<7>
  SA(2)  = GND
  VSS(20)  = GND
  DQ(37)  = M_B_DQ<37>
  VSS(19)  = GND
  DQ(33)  = M_B_DQ<33>
  VSS(18)  = GND
  DQS4N  = M_B_DQS_DN<4>
  DQS4P  = M_B_DQS_DP<4>
  VSS(17)  = GND
  DQ(39)  = M_B_DQ<39>
  VSS(16)  = GND
  DQ(35)  = M_B_DQ<35>
  VSS(15)  = GND
  DQ(45)  = M_B_DQ<45>
  VSS(14)  = GND
  DQ(41)  = M_B_DQ<41>
  VSS(13)  = GND
  DQS5N  = M_B_DQS_DN<5>
  DQS5P  = M_B_DQS_DP<5>
  VSS(12)  = GND
  DQ(47)  = M_B_DQ<47>
  VSS(11)  = GND
  DQ(43)  = M_B_DQ<43>
  VSS(10)  = GND
  DQ(53)  = M_B_DQ<53>
  VSS(9)  = GND
  DQ(49)  = M_B_DQ<49>
  VSS(8)  = GND
  DQS6N  = M_B_DQS_DN<6>
  DQS6P  = M_B_DQS_DP<6>
  VSS(7)  = GND
  DQ(55)  = M_B_DQ<55>
  VSS(6)  = GND
  DQ(51)  = M_B_DQ<51>
  VSS(5)  = GND
  DQ(61)  = M_B_DQ<61>
  VSS(4)  = GND
  DQ(57)  = M_B_DQ<57>
  VSS(3)  = GND
  DQS7N  = M_B_DQS_DN<7>
  DQS7P  = M_B_DQS_DP<7>
  VSS(2)  = GND
  DQ(63)  = M_B_DQ<63>
  VSS(1)  = GND
  DQ(59)  = M_B_DQ<59>
  VSS(0)  = GND
  VDDSPD  = PVPP_ABC
  SDA  = SMB_DDR_ABC_VPP_SDA
  VPP(1)  = PVPP_ABC
  VPP(0)  = PVPP_ABC
  VPP(2)  = PVPP_ABC

(kicad_pcb
	(version 20260206)
	(generator "pcbnew")
	(generator_version "10.0")
	(general
		(thickness 1.6)
		(legacy_teardrops no)
	)
	(paper "A4")
	(title_block
		(title "Wiwynn_Tioga_Pass_MB.brd")
		(comment 1 "Tioga Pass / footprint 2988 of 4770 (J6U1), pads 250-291 of 291")
	)
	(layers
		(0 "F.Cu" signal "TOP")
		(4 "In1.Cu" signal "L2GND")
		(6 "In2.Cu" signal "L3")
		(8 "In3.Cu" signal "L4GND")
		(10 "In4.Cu" signal "L5")
		(12 "In5.Cu" signal "L6GND")
		(14 "In6.Cu" signal "L7VCC")
		(16 "In7.Cu" signal "L8VCC")
		(18 "In8.Cu" signal "L9GND")
		(20 "In9.Cu" signal "L10")
		(22 "In10.Cu" signal "L11GND")
		(24 "In11.Cu" signal "L12")
		(26 "In12.Cu" signal "L13GND")
		(2 "B.Cu" signal "BOTTOM")
		(9 "F.Adhes" user "F.Adhesive")
		(11 "B.Adhes" user "B.Adhesive")
		(13 "F.Paste" user "Package Geometry/Pastemask Top")
		(15 "B.Paste" user "Package Geometry/Pastemask Bottom")
		(5 "F.SilkS" user "Ref Des/Silkscreen Top")
		(7 "B.SilkS" user "Ref Des/Silkscreen Bottom")
		(1 "F.Mask" user "Board Geometry/Soldermask Top")
		(3 "B.Mask" user "Board Geometry/Soldermask Bottom")
		(17 "Dwgs.User" user "User.Drawings")
		(19 "Cmts.User" user "User.Comments")
		(21 "Eco1.User" user "User.Eco1")
		(23 "Eco2.User" user "User.Eco2")
		(25 "Edge.Cuts" user "Board Geometry/Outline")
		(27 "Margin" user)
		(31 "F.CrtYd" user "Package Geometry/Place Bound Top")
		(29 "B.CrtYd" user "Package Geometry/Place Bound Bottom")
		(35 "F.Fab" user "Ref Des/Assembly Top")
		(33 "B.Fab" user "Ref Des/Assembly Bottom")
	)
	(footprint ""
		(layer "B.Cu")
		(at 194.700398 -15.222982 90)
		(property "Reference" "J6U1"
			(at 2.530348 39.10711 0)
			(unlocked yes)
			(layer "B.SilkS")
			(effects
				(font
					(size 0.7874 0.5842)
					(thickness 0.1524)
				)
				(justify left mirror)
			)
		)
		(property "Value" ""
			(at 0 0 90)
			(layer "B.Fab")
			(effects
				(font
					(size 1.27 1.27)
				)
				(justify mirror)
			)
		)
		(duplicate_pad_numbers_are_jumpers no)
		(pad "247" smd rect
			(at -4.59994 91.799918 270)
			(size 1.8034 0.508)
			(layers "B.Cu" "B.Mask" "B.Paste")
			(net "M_B_DQ<39>")
		)
		(pad "248" smd rect
			(at -4.59994 92.650056 270)
			(size 1.8034 0.508)
			(layers "B.Cu" "B.Mask" "B.Paste")
			(net "GND")
		)
		(pad "249" smd rect
			(at -4.59994 93.49994 270)
			(size 1.8034 0.508)
			(layers "B.Cu" "B.Mask" "B.Paste")
			(net "M_B_DQ<35>")
		)
		(pad "250" smd rect
			(at -4.59994 94.350078 270)
			(size 1.8034 0.508)
			(layers "B.Cu" "B.Mask" "B.Paste")
			(net "GND")
		)
		(pad "251" smd rect
			(at -4.59994 95.199962 270)
			(size 1.8034 0.508)
			(layers "B.Cu" "B.Mask" "B.Paste")
			(net "M_B_DQ<45>")
		)
		(pad "252" smd rect
			(at -4.59994 96.0501 270)
			(size 1.8034 0.508)
			(layers "B.Cu" "B.Mask" "B.Paste")
			(net "GND")
		)
		(pad "253" smd rect
			(at -4.59994 96.899984 270)
			(size 1.8034 0.508)
			(layers "B.Cu" "B.Mask" "B.Paste")
			(net "M_B_DQ<41>")
		)
		(pad "254" smd rect
			(at -4.59994 97.750122 270)
			(size 1.8034 0.508)
			(layers "B.Cu" "B.Mask" "B.Paste")
			(net "GND")
		)
		(pad "255" smd rect
			(at -4.59994 98.600006 270)
			(size 1.8034 0.508)
			(layers "B.Cu" "B.Mask" "B.Paste")
			(net "M_B_DQS_DN<5>")
		)
		(pad "256" smd rect
			(at -4.59994 99.44989 270)
			(size 1.8034 0.508)
			(layers "B.Cu" "B.Mask" "B.Paste")
			(net "M_B_DQS_DP<5>")
		)
		(pad "257" smd rect
			(at -4.59994 100.300028 270)
			(size 1.8034 0.508)
			(layers "B.Cu" "B.Mask" "B.Paste")
			(net "GND")
		)
		(pad "258" smd rect
			(at -4.59994 101.149912 270)
			(size 1.8034 0.508)
			(layers "B.Cu" "B.Mask" "B.Paste")
			(net "M_B_DQ<47>")
		)
		(pad "259" smd rect
			(at -4.59994 102.00005 270)
			(size 1.8034 0.508)
			(layers "B.Cu" "B.Mask" "B.Paste")
			(net "GND")
		)
		(pad "260" smd rect
			(at -4.59994 102.849934 270)
			(size 1.8034 0.508)
			(layers "B.Cu" "B.Mask" "B.Paste")
			(net "M_B_DQ<43>")
		)
		(pad "261" smd rect
			(at -4.59994 103.700072 270)
			(size 1.8034 0.508)
			(layers "B.Cu" "B.Mask" "B.Paste")
			(net "GND")
		)
		(pad "262" smd rect
			(at -4.59994 104.549956 270)
			(size 1.8034 0.508)
			(layers "B.Cu" "B.Mask" "B.Paste")
			(net "M_B_DQ<53>")
		)
		(pad "263" smd rect
			(at -4.59994 105.400094 270)
			(size 1.8034 0.508)
			(layers "B.Cu" "B.Mask" "B.Paste")
			(net "GND")
		)
		(pad "264" smd rect
			(at -4.59994 106.249978 270)
			(size 1.8034 0.508)
			(layers "B.Cu" "B.Mask" "B.Paste")
			(net "M_B_DQ<49>")
		)
		(pad "265" smd rect
			(at -4.59994 107.100116 270)
			(size 1.8034 0.508)
			(layers "B.Cu" "B.Mask" "B.Paste")
			(net "GND")
		)
		(pad "266" smd rect
			(at -4.59994 107.95 270)
			(size 1.8034 0.508)
			(layers "B.Cu" "B.Mask" "B.Paste")
			(net "M_B_DQS_DN<6>")
		)
		(pad "267" smd rect
			(at -4.59994 108.799884 270)
			(size 1.8034 0.508)
			(layers "B.Cu" "B.Mask" "B.Paste")
			(net "M_B_DQS_DP<6>")
		)
		(pad "268" smd rect
			(at -4.59994 109.650022 270)
			(size 1.8034 0.508)
			(layers "B.Cu" "B.Mask" "B.Paste")
			(net "GND")
		)
		(pad "269" smd rect
			(at -4.59994 110.499906 270)
			(size 1.8034 0.508)
			(layers "B.Cu" "B.Mask" "B.Paste")
			(net "M_B_DQ<55>")
		)
		(pad "270" smd rect
			(at -4.59994 111.350044 270)
			(size 1.8034 0.508)
			(layers "B.Cu" "B.Mask" "B.Paste")
			(net "GND")
		)
		(pad "271" smd rect
			(at -4.59994 112.199928 270)
			(size 1.8034 0.508)
			(layers "B.Cu" "B.Mask" "B.Paste")
			(net "M_B_DQ<51>")
		)
		(pad "272" smd rect
			(at -4.59994 113.050066 270)
			(size 1.8034 0.508)
			(layers "B.Cu" "B.Mask" "B.Paste")
			(net "GND")
		)
		(pad "273" smd rect
			(at -4.59994 113.89995 270)
			(size 1.8034 0.508)
			(layers "B.Cu" "B.Mask" "B.Paste")
			(net "M_B_DQ<61>")
		)
		(pad "274" smd rect
			(at -4.59994 114.750088 270)
			(size 1.8034 0.508)
			(layers "B.Cu" "B.Mask" "B.Paste")
			(net "GND")
		)
		(pad "275" smd rect
			(at -4.59994 115.599972 270)
			(size 1.8034 0.508)
			(layers "B.Cu" "B.Mask" "B.Paste")
			(net "M_B_DQ<57>")
		)
		(pad "276" smd rect
			(at -4.59994 116.45011 270)
			(size 1.8034 0.508)
			(layers "B.Cu" "B.Mask" "B.Paste")
			(net "GND")
		)
		(pad "277" smd rect
			(at -4.59994 117.299994 270)
			(size 1.8034 0.508)
			(layers "B.Cu" "B.Mask" "B.Paste")
			(net "M_B_DQS_DN<7>")
		)
		(pad "278" smd rect
			(at -4.59994 118.149878 270)
			(size 1.8034 0.508)
			(layers "B.Cu" "B.Mask" "B.Paste")
			(net "M_B_DQS_DP<7>")
		)
		(pad "279" smd rect
			(at -4.59994 119.000016 270)
			(size 1.8034 0.508)
			(layers "B.Cu" "B.Mask" "B.Paste")
			(net "GND")
		)
		(pad "280" smd rect
			(at -4.59994 119.8499 270)
			(size 1.8034 0.508)
			(layers "B.Cu" "B.Mask" "B.Paste")
			(net "M_B_DQ<63>")
		)
		(pad "281" smd rect
			(at -4.59994 120.700038 270)
			(size 1.8034 0.508)
			(layers "B.Cu" "B.Mask" "B.Paste")
			(net "GND")
		)
		(pad "282" smd rect
			(at -4.59994 121.549922 270)
			(size 1.8034 0.508)
			(layers "B.Cu" "B.Mask" "B.Paste")
			(net "M_B_DQ<59>")
		)
		(pad "283" smd rect
			(at -4.59994 122.40006 270)
			(size 1.8034 0.508)
			(layers "B.Cu" "B.Mask" "B.Paste")
			(net "GND")
		)
		(pad "284" smd rect
			(at -4.59994 123.249944 270)
			(size 1.8034 0.508)
			(layers "B.Cu" "B.Mask" "B.Paste")
			(net "PVPP_ABC")
		)
		(pad "285" smd rect
			(at -4.59994 124.100082 270)
			(size 1.8034 0.508)
			(layers "B.Cu" "B.Mask" "B.Paste")
			(net "SMB_DDR_ABC_VPP_SDA")
		)
		(pad "286" smd rect
			(at -4.59994 124.949966 270)
			(size 1.8034 0.508)
			(layers "B.Cu" "B.Mask" "B.Paste")
			(net "PVPP_ABC")
		)
		(pad "287" smd rect
			(at -4.59994 125.800104 270)
			(size 1.8034 0.508)
			(layers "B.Cu" "B.Mask" "B.Paste")
			(net "PVPP_ABC")
		)
		(pad "288" smd rect
			(at -4.59994 126.649988 270)
			(size 1.8034 0.508)
			(layers "B.Cu" "B.Mask" "B.Paste")
			(net "PVPP_ABC")
		)
	)
)
